# BARRELEYE_G2-MB-PVT-X04-HW-BOM-X26_20180122_Final.xls.xlsx — DEPOP (bom)
| FOXCONN TECHNOLOGY GROUP |  |  |  |  |  |  |  |  |  |  |  |  |
| BILL OF MATERIAL |  |  |  |  |  |  |  |  |  |  |  |  |
| REV OF  BOM | X26 | CUSTOMER | RACKSPACE |  | CUSTOMER P/N |  | PRODUCT CODE |  | PWA  REV | X04 | DATE | 43122 |
| Sourcing (Single/Sole/Multi) | Critical Commodity (Y or N) | Component Class (1, 2, other) | Customer PSL (Y or N) | Item Number | Foxconn P/N | Customer P/N | Part Description | Manufacturer  Full Name | Manufacturer  Part Number | Qty | RoHS Status | Location |
|  | Y | 2 | Y(3) | 1 | 62010FF00-015-G | - | CAP,47pF,+/-5%,NPO(C0G),50V,G,SMD0402 | MURATA ELEC. NORTH AMERICA | GRM1555C1H470J | 38 | Y | C1,C2,C3,C4,C7,C8,C16,C17,C18,C19,C20,C21,C22,C23,C24,C25,C26,C27,C28,C29,C30,C31,C32,C726,C727,C728,C729,C739,C740,C741,C742,C743,C744,C745,C746,C747,C748,C2180 |
|  | ND | ND | Y(3) | 2 | 620103700-015-G | - | CAP,100nF,+/-10%,X7R,10V,G,SMD0402 | MURATA ELEC. NORTH AMERICA | GRM155R71A104K | 4 | Y | C37,C204,C205,C753 |
|  | Y | ND | Y(1) | 3 | 62012WD00-015-G | - | CAP,4.7uF,+/-20%,X6S,6.3V,G,SMD0402 | MURATA ELEC. NORTH AMERICA | GRM155C80J475MEAAD | 2 |  | C60,C757 |
|  | Y | 2 | Y(3) | 4 | 62011DF01-015-G | - | CAP,220nF,+/-10%,X7R,16V,G,SMD0402 | MURATA ELEC. NORTH AMERICA | GRM155R71C224K | 8 | N | C80,C83,C138,C794,C795,C814,C897,C904 |
|  | Y | 2 | Y(3) | 5 | 620107G00-015-G | - | CAP,47nF,+/-10%,X7R,16V,G,SMD0402 | MURATA ELEC. NORTH AMERICA | GRM155R71C473K | 3 | N | C184,C231,C232 |
|  | ND | ND | N | 6 | 62012NU00-015-G | - | CAP,1uF,+/-10%,X7R,6.3V,G,SMD0402 | MURATA ELEC. NORTH AMERICA | GRM155R70J105KA12D | 1 | N | C202 |
|  | ND |  | Y(1) | 7 | 62012PS00-015-G |  | CAP,10uF,+/-20%,X6S,4V,G,SMD0402 | MURATA ELEC. NORTH AMERICA | GRM155C80G106M | 10 |  | PBFC61,PBEC61,PAFC61,PAEC61,PBMC62,PAMC62,PBAC126,PAAC126,C264,C2171 |
|  | Y | ND | Y(3) | 8 | 62011U701-015-G | - | CAP,10nF,+/-10%,X7R,6.3V,G,SMD0402 | MURATA ELEC. NORTH AMERICA | GRM155R70J103K | 1 |  | C1511 |
|  | ND | ND | Y(3) | 9 | 62010BJ00-015-G | - | CAP,56pF,+/-5%,NPO(C0G),50V,G,SMD0402 | MURATA ELEC. NORTH AMERICA | GRM1555C1H560J | 2 | N | C1553,C1558 |
|  | Y | 2 | Y(3) | 10 | 62010GW00-015-G | - | CAP,10pF,+/-5%,NPO,50V,G,SMD0402 | MURATA ELEC. NORTH AMERICA | GRM1555C1H100J | 18 | N | PBMC8,PBFC8,PBEC8,PBAC8,PAMC8,PAFC8,PAEC8,PAAC8,PBMC9,PBFC9,PBEC9,PBAC9,PAMC9,PAFC9,PAEC9,PAAC9,C1556,C1557 |
|  | Y | 2 | Y(3) | 11 | 620101T02-015-G | - | CAP,100nF,+/-10%,X7R,16V,G,SMD0402 | MURATA ELEC. NORTH AMERICA | GRM155R71C104K | 8 | Y | PSPC13,PIPC13,PFPC13,PEPC13,C2004,C2005,C2006,C2007 |
|  | ND | ND | Y(3) | 12 | 620108100-015-G | - | CAP,15pF,+/-5%,NPO(C0G),50V,G,SMD0402 | MURATA ELEC. NORTH AMERICA | GRM1555C1H150J | 2 | N | C2008,C2010 |
|  | Y |  | Y(1) | 13 | 620130V00-015-G |  | CAP,10uF,+/-20%,X6S,16V,G,SMD0603 | MURATA ELEC. NORTH AMERICA | GRM188C81C106MA73D | 4 |  | C2013,C2015,C2017,C2019 |
|  | ND | ND | Y(3) | 14 | 620100L00-015-G | - | CAP,22pF,+/-5%,NPO(C0G),50V,G,SMD0402 | MURATA ELEC. NORTH AMERICA | GRM1555C1H220J | 4 | Y | C2014,C2016,C2018,C2020 |
|  | ND | ND | Y(3) | 15 | 62010QB00-015-G | - | CAP,10nF,+/-10%,X7R,50V,G,SMD0402 | MURATA ELEC. NORTH AMERICA | GRM155R71H103K | 11 | N | PSRC1,PSTC9,PSLC9,PSFC9,PSEC9,PSDC9,PQPC9,PFRC9,PEEC9,PEDC9,C2071 |
|  | ND | ND | Y(1) | 16 | 62012A400-015-G | - | CAP,100nF,+/-10%,X7R,25V,G,SMD0402 | MURATA ELEC. NORTH AMERICA | GRM155R71E104KE14D | 1 | N | C2097 |
|  | ND | ND | Y(1) | 17 | 62010P501-015-G | - | CAP,1nF,+/-10%,X7R,16V,G,SMD0402 | MURATA ELEC. NORTH AMERICA | GRM155R71C102KA01D | 1 | N | C2111 |
|  | Y | 2 | ND | 18 | 620108000-015-G | - | CAP,100pF,+/-5%,NPO(C0G),50V,G,SMD0402 | MURATA ELEC. NORTH AMERICA | GRM1555C1H101J | 1 | Y | C2136 |
|  | ND | ND | Y(3) | 19 | 620108B00-015-G | - | CAP,120pF,+/-5%,NPO(C0G),50V,G,SMD0402 | MURATA ELEC. NORTH AMERICA | GRM1555C1H121J | 4 | N | C2182,C2183,C2184,C2185 |
|  | ND | ND | N | 20 | 521803M00-227-G |  | Diode,Array-TVS,UCLAMP0508T.TCT,Level 4,5V,G,SLP,SMD-9 | SEMTECH CORPORATION. | UCLAMP0508T.TCT | 1 | Y | DN1 |
|  | Y | 1 | Y(3) | 21 | 520305M00-223-G | DC005 | DIODE,Schottky Rectifier,MBRS340T3G,40V,3A,G,SMC,SMD | ON SEMICONDUCTOR CORP | MBRS340T3G | 8 | N | D1,D2,D3,D4,D5,D6,D7,D51 |
|  | ND | ND | N | 22 | 520100200-237-G |  | DIODE,Switching,1N4148W-7-F,100V,0.15A,G,SOD123-2,SMD | DIODES INEORPORATION | 1N4148W-7-F | 4 | N | D29,D30,D31,D32 |
|  | ND |  | N | 23 | 520306F00-223-G |  | DIODE,Schottky,NSR0320MW2T1G,20V,1A,G,SOD323-2,SMD | ON SEMICONDUCTOR CORP | NSR0320MW2T1G | 1 | N | D52 |
|  | ND |  | Y(1) | 24 | 0438005.WRGT |  | Fuse,Fast acting,32V,5A,G,SMD0603 | LITTELFUSE FAR EAST PTE LTD | 0438005.WRGT | 4 | Y | FS23,FS24,FS25,FS26 |
|  | ND | ND | Y(1) | 25 | 730101C00-086-G |  | Fuse,Slow blow,125V,30A,G,SMD | LITTELFUSE FAR EAST PTE LTD | 0456030.ER | 1 | N | FS30 |
|  | N | 1 | N | 26 | 52111AE00-289-G |  | LED,Ora,LTST-C281KFKT-5A,5V,30mA,G,SMD0402 | LITE-ON TECHNOLOGY CORPORATION | LTST-C281KFKT-5A | 1 |  | LED4 |
|  | N | 1 | N | 27 | 52111J100-289-G |  | LED,Gre,LTST-C281KGKT-5A,2.3V,30mA,G,SMD0402 | LITE-ON TECHNOLOGY CORPORATION | LTST-C281KGKT-5A | 1 |  | LED5 |
|  | N |  | Y(1) | 28 | 62011J601-015-G |  | CAP,2.2uF,+/-10%,X7R,100V,G,SMD1210 | MURATA ELEC. NORTH AMERICA | GRM32ER72A225K | 8 |  | PBMC20,PBFC20,PAMC20,PAEC20,PBEC21,PBAC21,PAFC21,PAAC21 |
|  | N | ND | Y(3) | 29 | 62012GY00-015-G | - | CAP,100nF,+/-20%,X7R,25V,G,SMD0402 | MURATA ELEC. NORTH AMERICA | GRM155R71E104M | 16 |  | PBMC23,PBFC23,PBEC23,PAMC23,PAFC23,PAEC23,PBMC24,PBFC24,PBEC24,PBAC24,PAMC24,PAFC24,PAEC24,PAAC24,PBAC25,PAAC25 |
|  | ND | ND | Y(1) | 30 | 62011DA00-015-G | - | CAP,1uF,+/-10%,X7R,100V,G,SMD1206 | MURATA ELEC. NORTH AMERICA | GRM31CR72A105K | 14 | Y | PBFC26,PBEC26,PAFC26,PAEC26,PBMC28,PBAC28,PAMC28,PAAC28,PBAC79,PAAC79,PBAC80,PAAC80,PBAC112,PAAC112 |
|  | ND | ND | Y(3) | 31 | 62010VD00-015-G |  | CAP,100nF,+/-10%,X7R,100V,G,SMD0603 | MURATA ELEC. NORTH AMERICA | GRM188R72A104K | 14 |  | PBFC401,PBEC401,PBAC401,PAMC401,PAFC401,PAEC401,PAAC401,PBFC402,PBEC402,PBAC402,PAMC402,PAFC402,PAEC402,PAAC402 |
|  | Y |  | Y(1) | 32 | 62012RJ00-015-G |  | CAP,4.7uF,+/-10%,X6S,16V,G,SMD0603 | MURATA ELEC. NORTH AMERICA | GRM188C81C475K | 2 |  | PBAC451,PAAC451 |
|  | ND |  | N | 33 | 52030W700-237-G |  | DIODE,Schottky,BAT54WT-7,30V,100mA,G,SOD523-2,SMD | DIODES INEORPORATION | BAT54WT-7 | 8 |  | PBMD2,PBFD2,PBED2,PBAD2,PAMD2,PAFD2,PAED2,PAAD2 |
|  | ND |  | N | 34 | 52030TQ00-237-G |  | Diode,Schottky,BAS40-06-7-F,40V,200mA,G,SOT-23-3,SMD | DIODES INCORPORATION | BAS40-06-7-F | 2 | N | PBAD4,PAAD4 |
|  | N |  | N | 35 | 63035NQ00-029-G |  | IND,0.1uH@100KHz,+/-20%,11.5A,6mOhm,SHLD,G,SMD | VISHAY ENTER TECHNO LOGY.INC | IHLP1616ABERR10M01 | 2 |  | PBAL4,PAAL4 |
|  | N | ND | Y(4) | 36 | 610107A00-017-G | - | RES,0 Ohm,+/-5%,1/16W,G,SMD0402 | KOA SPEER ELECTRONICS, INC. | RK73Z1ETTP | 311 | N | PSUR3,PSRR5,PBFR5,PBER5,PAFR5,PAER5,PBFR6,PBER6,PBAR6,PAFR6,PAER6,PBMR7,PBAR7,PAFR7,PAAR7,PSTR8,PSER8,PBFR8,PBER8,PAAR8,PAER9,PBAR10,PAMR10,PHAR11,PBFR11,PAAR11,PBMR12,PBER12,PAER12,PSTR13,PSLR13,PSFR13,PSER13,PSDR13,PQPR13,PFRR13,PEER13,PEDR13,PBAR13,PAFR13,PAER13,PAMR15,PHAR16,PBFR16,PBER16,PAFR16,PAAR16,PSPR17,PIPR17,PHAR17,PFPR17,PEPR17,PHAR18,PBMR19,PBFR19,PBER19,PBAR19,PAMR19,PAFR19,PAER19,PAAR19,PBMR20,PBFR20,PBER20,PBAR20,PAMR20,PAFR20,PAER20,PAAR20,PBMR23,PBFR23,PBER23,PBAR23,PAMR23,PAFR23,PAER23,PAAR23,PSRR24,PHAR26,PHAR27,PBNR28,PANR28,PBMR29,PBFR29,PBER29,PBAR29,PAMR29,PAFR29,PAER29,PAAR29,PBMR31,PBFR31,PBER31,PBAR31,PAMR31,PAFR31,PAER31,PAAR31,PBMR37,PBFR37,PBER37,PBAR37,PAMR37,PAFR37,PAER37,PAAR37,PBMR73,PAMR73,PBER76,PBAR76,PAFR76,PAER76,PAAR76,PBFR77,PBMR80,PAMR80,PBAR82,PAFR82,PAAR82,PBMR83,PBFR83,PBAR83,PAMR83,PAAR83,PBMR84,PAMR84,PBER86,PAFR86,PAER86,PBFR87,PBAR87,PAAR87,PBER88,PBAR88,PAFR88,PAER88,PAAR88,PBFR89,PBAR99,PAAR99,PBMR101,PAMR101,PBER103,PAFR103,PAER103,PBFR104,PBMR105,PAMR105,PBMR106,PAMR106,PBER107,PBAR107,PAFR107,PAER107,PAAR107,PBMR108,PBFR108,PBER108,PAMR108,PAFR108,PAER108,PBFR109,PBER110,PAFR110,PAER110,PBFR111,PBAR111,PAAR111,PBMR112,PBAR112,PAMR112,PAAR112,PBMR114,PBER114,PBAR114,PAMR114,PAFR114,PAER114,PAAR114,PBFR115,PBER116,PAFR116,PAER116,PBFR117,PBAR118,PAAR118,PBMR119,PAMR119,PBMR120,PBAR120,PAMR120,PAAR120,PBER121,PAFR121,PAER121,PBFR122,PBER122,PAFR122,PAER122,PBFR123,PBAR125,PAAR125,PBAR126,PAAR126,PBFR304,PBER304,PAFR304,PAER304,PBFR308,PAFR308,PAER308,PBFR309,PBER309,PAFR309,PAER309,PBER310,PBMR311,PBFR311,PBAR311,PAMR311,PAFR311,PAER311,PAAR311,PBMR312,PBER312,PBAR312,PAMR312,PAAR312,PBAR313,PAAR313,PBMR450,PBFR450,PBER450,PBAR450,PAMR450,PAFR450,PAER450,PAAR450,PAAR451,PBAR452,PAAR452,PBAR454,PBMR610,PBAR610,PAMR610,PAAR610,PBAR611,PAAR611,PBAR612,PAAR612,PAFR635,R653,R654,R655,R656,R659,PBFR660,PBER660,R661,R662,PAER685,R752,R803,R819,R821,R948,R1071,R1087,R1101,R1103,R1107,R1120,R1121,R1122,R1123,R1124,R1142,R1144,R1230,R1264,R1268,R1272,R1276,R1287,R1452,R1453,R1454,R1455,R1456,R1457,R1458,R1459,R1472,R1479,R1486,R1489,R1529,R1530,R1554,R1557,R1815,R1816,R1817,R1818,R1819,R1850,PSRR3004,PEPR3008,PIPR3009,PFPR3009,PSPR3014 |
|  | N | ND | Y(4) | 37 | 61010G500-017-G | - | RES,10KOhm,+/-1%,1/16W,G,SMD0402 | KOA SPEER ELECTRONICS, INC. | RK73H1ETTP1002F | 54 | N | PHAR3,PBMR51,PBFR51,PBER51,PBAR51,PAMR51,PAFR51,PAER51,PAAR51,PBMR52,PBFR52,PBER52,PBAR52,PAMR52,PAFR52,PAER52,PAAR52,PBMR53,PBFR53,PBER53,PBAR53,PAMR53,PAFR53,PAER53,PAAR53,PBMR71,PAMR71,PBMR72,PAMR72,PBER73,PBAR73,PAFR73,PAER73,PAAR73,PBFR74,PBER75,PBAR75,PAFR75,PAER75,PAAR75,PBFR76,R903,R904,R905,R906,R907,R908,R920,R953,R1013,R1014,R1415,R1790,PSRR3007 |
|  | N | Other | Y(4) | 38 | 610130Y00-017-G |  | RES,1 Ohm,+/-1%,1/3W,G,SMD1206 | KOA SPEER ELECTRONICS, INC. | SR732BTTD1R00F | 10 |  | PBMR60,PBAR60,PAMR60,PAAR60,PBER63,PAFR63,PAER63,PBFR64,PBAR100,PAAR100 |
|  | N | ND | Y(4) | 39 | 610108300-017-G | - | RES,0 Ohm,+/-5%,1/10W,G,SMD0603 | KOA SPEER ELECTRONICS, INC. | RK73Z1JTTD | 19 | N | PBNR1,PANR1,PBMR67,PAMR69,PBAR74,PAAR74,PBER80,PAFR80,PAER80,PBFR81,PAER123,PBFR520,PBER520,PAFR520,PBMR609,PBAR609,PAMR609,PAAR609,R1845 |
|  | N | ND | Y(4) | 40 | 61010L300-017-G | - | RES,1KOhm,+/-1%,1/16W,G,SMD0402 | KOA SPEER ELECTRONICS, INC. | RK73H1ETTP1001F | 15 | N | R14,R15,PBMR310,PBAR310,PAMR310,PAAR310,R377,R378,R657,R660,R1499,R1729,R1733,R1737,R1741 |
|  | ND | ND | Y(4) | 41 | 61010L100-017-G | - | RES,100KOhm,+/-1%,1/16W,G,SMD0402 | KOA SPEER ELECTRONICS, INC. | RK73H1ETTP1003F | 8 | N | PBFR517,PBER517,PAFR517,PAER518,PBMR602,PBAR602,PAMR602,PAAR602 |
|  | N |  | N | 42 | 880302200-53N-G |  | Converter,input 0V~60V,185W,G,VTM48MP012T130AA0 | Vicor Corporation | VTM48MP012T130AA0 | 2 |  | PBAU5,PAAU5 |
|  | N |  | Y(3) | 43 | 62120ER01-024-G |  | ECAP,SPEA,470uF,+/-20%,2.5V,105C,G,SMD2816,ESR<=3mOhm | PANASONIC INDUSTRIAL CO.,LTD. | EEFGX0E471R | 8 |  | PBECE7,PAFCE7,PAECE7,PBFCE8,PBECE8,PAFCE8,PAECE8,PBFCE9 |
|  | ND | ND | Y(1) | 44 | 62010L800-015-G | - | CAP,1nF,+/-5%,NPO(C0G),50V,G,SMD0402 | MURATA ELEC. NORTH AMERICA | GRM1555C1H102J | 5 | N | PBFC5,PBEC5,PAFC5,PAEC5,PSRC8 |
|  | ND | ND | Y(4) | 45 | 61010PS00-017-G | - | RES,200KOhm,+/-1%,1/16W,G,SMD0402 | KOA SPEER ELECTRONICS, INC. | RK73H1ETTP2003F | 4 | N | PBFR9,PBER10,PAFR12,PAER14 |
|  | ND | ND | Y(4) | 46 | 610114S00-017-G | - | RES,4.99KOhm,+/-1%,1/16W,G,SMD0402 | KOA SPEER ELECTRONICS, INC. | RK73H1ETTP4991F | 4 | N | PBFR39,PBER39,PAFR39,PAER39 |
|  | ND |  | Y(1) | 47 | 62012UU00-015-G |  | CAP,100uF,+/-20%,X6S,4V,G,SMD0805 | MURATA ELEC. NORTH AMERICA | GRM21BC80G107ME15L | 2 |  | PBNC24,PANC24 |
|  | ND | ND | Y(4) | 48 | 61010LA00-017-G | - | RES,4.7KOhm,+/-1%,1/16W,G,SMD0402 | KOA SPEER ELECTRONICS, INC. | RK73H1ETTP4701F | 48 | N | PSPR1,PIPR1,PFPR1,PEPR1,PBNR2,PANR2,PSRR6,PBNR9,PANR9,PSPR16,PIPR16,PFPR16,PEPR16,R352,R354,R358,R360,R663,R681,R682,R684,R685,R686,R687,R708,R709,R710,R731,R732,R897,R939,R1001,R1119,R1126,R1153,R1240,R1263,R1267,R1271,R1275,R1294,R1526,R1533,R1548,PSPR3005,PIPR3005,PFPR3005,PEPR3005 |
|  | ND |  | N | 49 | 61011G200-017-G |  | RES,12.4KOhm,+/-1%,1/16W,G,SMD0402 | KOA SPEER ELECTRONICS, INC. | RK73H1ETTP1242F | 2 | N | PBNR8,PANR8 |
|  | N | ND | Y(4) | 50 | 610114A00-017-G |  | RES,24.9KOhm,+/-1%,1/16W,G,SMD0402 | KOA SPEER ELECTRONICS, INC. | RK73H1ETTP2492F | 2 | N | PBNR19,PANR19 |
|  | ND |  | Y(4) | 51 | 61011CL00-017-G |  | RES,66.5KOhm,+/-1%,1/16W,G,SMD0402 | KOA SPEER ELECTRONICS, INC. | RK73H1ETTP6652F | 2 | N | PBNR25,PANR25 |
|  | ND | ND | N | 52 | 62010HR00-015-G | - | CAP,100nF,+/-10%,X7R,50V,G,SMD0603 | MURATA ELEC. NORTH AMERICA | GRM188R71H104K | 11 | N | PUAC9,PSIC9,PSAC9,PRAC9,PQAC9,PPAC9,PIAC9,PFAC9,PETC9,PERC9,PEAC9 |
|  | Y | 2 | Y(4) | 53 | 620103K00-015-G | - | CAP,1nF,+/-10%,X7R,50V,G,SMD0402 | MURATA ELEC. NORTH AMERICA | GRM155R71H102K | 11 | N | PUAC17,PSIC17,PSAC17,PRAC17,PQAC17,PPAC17,PIAC17,PFAC17,PETC17,PERC17,PEAC17 |
|  | Y | 2 | Y(4) | 54 | 620105U00-015-G | - | CAP,220pF,+/-10%,X7R,50V,G,SMD0402 | MURATA ELEC. NORTH AMERICA | GRM155R71H221K | 9 | N | PSTC13,PSLC13,PSFC13,PSEC13,PSDC13,PQPC13,PFRC13,PEEC13,PEDC13 |
|  | N | ND | Y(4) | 55 | 610112M00-017-G |  | RES,13KOhm,+/-1%,1/16W,G,SMD0402 | KOA SPEER ELECTRONICS, INC. | RK73H1ETTP1302F | 8 | N | PSTR1,PSLR1,PSFR1,PSER1,PSDR1,PQPR1,PEER1,PEDR1 |
|  | N | ND | Y(4) | 56 | 610114H00-017-G | - | RES,20KOhm,+/-1%,1/16W,G,SMD0402 | KOA SPEER ELECTRONICS, INC. | RK73H1ETTP2002F | 12 | N | PSTR3,PSLR3,PSFR3,PSER3,PSDR3,PQPR3,PEER3,PEDR3,R1757,R1758,R1759,R1760 |
|  | ND | ND | Y(4) | 57 | 61011HA00-017-G |  | RES,1 Ohm,+/-1%,1/16W,G,SMD0402 | KOA SPEER ELECTRONICS, INC. | RK73H1ETTP1R00F | 10 | N | PSTR14,PSLR14,PSFR14,PSER14,PSDR14,PQPR14,PFRR14,PEER14,PEDR14,PSRR19 |
|  | ND | ND | Y(4) | 58 | 61011H300-017-G |  | RES,316 Ohm,+/-1%,1/16W,G,SMD0402 | KOA SPEER ELECTRONICS, INC. | RK73H1ETTP3160F | 8 | N | PSPR18,PIPR18,PFPR18,PEPR18,PIPR3008,PFPR3008,PEPR3009,PSPR3015 |
|  | N |  | Y(5) | 59 | 61100LR00-017-G |  | RES,100 Ohm,+/-1%,1/16W,G,SMD0402 | KOA SPEER ELECTRONICS, INC. | RN731ETTP1000F50 | 9 |  | PSPR19,PIPR19,PFPR19,PEPR19,R1265,R1269,R1273,R1277,R1485 |
|  | ND | ND | Y(5) | 60 | 61100BP00-017-G |  | RES,3.09KOhm,+/-0.1%,1/16W,G,SMD0402 | KOA SPEER ELECTRONICS, INC. | RN731ETTP3091B25 | 4 | Y | PSPR3006,PIPR3006,PFPR3006,PEPR3006 |
|  | ND |  | Y(5) | 61 | 61100N100-017-G |  | RES,2.37KOhm,+/-0.1%,1/16W,G,SMD0402 | KOA SPEER ELECTRONICS, INC. | RN731ETTP2371B25 | 1 | Y | PSRR3 |
|  | ND |  | Y(5) | 62 | 61100PK00-017-G |  | RES,10.7KOhm,+/-0.1%,1/16W,G,SMD0402 | KOA SPEER ELECTRONICS, INC. | RN731ETTP1072B25 | 1 |  | PSRR4 |
|  | N |  | Y(5) | 63 | 61100D400-017-G |  | RES,1.87KOhm,+/-0.1%,1/16W,G,SMD0402 | KOA SPEER ELECTRONICS, INC. | RN731ETTP1871B25 | 1 | Y | PSRR10 |
|  | N | ND | Y(4) | 64 | 610109900-017-G | - | RES,1KOhm,+/-1%,1/10W,G,SMD0603 | KOA SPEER ELECTRONICS, INC. | RK73H1JTTD1001F | 1 | N | PSRR21 |
|  | ND |  | Y(5) | 65 | 61100PM00-017-G |  | RES,453 Ohm,+/-0.1%,1/16W,G,SMD0402 | KOA SPEER ELECTRONICS, INC. | RN731ETTP4530B25 | 1 |  | PSRR23 |
|  | N |  | N | 66 | 880302300-065-G |  | Converter,input 40V~60V,600W,G,Q54SJ12050NNDH | DELTA ELECTRONICS INDUSTRIAL CO.,LTD | Q54SJ12050NNDH | 1 |  | PSUU2 |
|  | ND | ND | Y(3) | 67 | 510100W00-237-G | - | TRANS N,MMBT3904-7-F,40V,0.2A,G,SOT23-3,SMD | DIODES INEORPORATION | MMBT3904-7-F | 7 | N | Q86,Q87,Q88,Q89,Q90,Q91,Q92 |
|  | ND | ND | Y(4) | 68 | 61010FG00-017-G | - | RES,20KOhm,+/-5%,1/16W,G,SMD0402 | KOA SPEER ELECTRONICS, INC. | RK73B1ETTP203J | 5 | N | R60,R61,R62,R63,R64 |
|  | ND | ND | Y(4) | 69 | 61011WQ00-017-G | - | RES,3KOhm,+/-1%,1/16W,G,SMD0402 | KOA SPEER ELECTRONICS, INC. | RK73H1ETTP3001F | 2 | N | R67,R1799 |
|  | ND | ND | Y(4) | 70 | 610102C00-017-G | - | RES,15KOhm,+/-5%,1/16W,G,SMD0402 | KOA SPEER ELECTRONICS, INC. | RK73B1ETTP153J | 2 | N | R77,R1800 |
|  |  |  | Y(4) | 71 | 61010KJ00-017-G |  | RES,3.3KOhm,+/-5%,1/16W,G,SMD0402 | KOA SPEER ELECTRONICS, INC. | RK73B1ETTP332J | 22 | N | R90,R443,R1030,R1036,R1037,R1038,R1039,R1040,R1045,R1046,R1049,R1052,R1053,R1056,R1057,R1058,R1061,R1062,R1065,R1066,R1231,R1338 |
|  | N | ND | Y(4) | 72 | 610102700-017-G | - | RES,49.9 Ohm,+/-1%,1/16W,G,SMD0402 | KOA SPEER ELECTRONICS, INC. | RK73H1ETTP49R9F | 121 | N | R91,R92,R93,R102,R118,R119,R120,R134,R135,R136,R144,R145,R149,R156,R157,R159,R165,R168,R170,R176,R178,R181,R185,R190,R191,R199,R201,R202,R210,R211,R212,R218,R219,R220,R228,R229,R233,R241,R242,R243,R249,R252,R254,R260,R262,R265,R269,R274,R275,R283,R285,R286,R294,R295,R296,R444,R450,R451,R462,R489,R490,R491,R499,R500,R504,R511,R512,R514,R520,R523,R525,R532,R534,R536,R540,R545,R546,R554,R556,R557,R565,R566,R567,R573,R574,R575,R583,R584,R588,R595,R596,R598,R604,R607,R609,R616,R618,R619,R624,R629,R630,R638,R640,R641,R649,R650,R651,R1140,R1279,R1399,R1400,R1403,R1404,R1405,R1791,R1792,R1793,R1794,R1795,R1796,R1811 |
|  |  |  | Y(4) | 73 | 610112W00-017-G |  | RES,2KOhm,+/-5%,1/16W,G,SMD0402 | KOA SPEER ELECTRONICS, INC. | RK73B1ETTP202J | 2 | N | R96,R448 |
|  | N | other | Y(4) | 74 | 610107C00-017-G | K9577 | RES,10KOhm,+/-5%,1/16W,G,SMD0402 | KOA SPEER ELECTRONICS, INC. | RK73B1ETTP103J | 3 | N | R116,R305,R471 |
|  | N | other | Y(4) | 75 | 61010FL00-017-G |  | RES,2.2KOhm,+/-5%,1/16W,G,SMD0402 | KOA SPEER ELECTRONICS, INC. | RK73B1ETTP222J | 14 | N | R667,R672,R675,R676,R691,R692,R693,R694,R695,R696,R697,R698,R716,R718 |
|  | N | other | Y(4) | 76 | 610100T00-017-G |  | RES,1KOhm,+/-5%,1/16W,G,SMD0402 | KOA SPEER ELECTRONICS, INC. | RK73B1ETTP102J | 6 | N | R703,R707,R712,R713,R714,R737 |
|  | ND | ND | Y(4) | 77 | 61011KS00-017-G | - | RES,47KOhm,+/-1%,1/16W,G,SMD0402 | KOA SPEER ELECTRONICS, INC. | RK73H1ETTP4702F | 1 | N | R720 |
|  | ND | ND | Y(4) | 78 | 61011H500-017-G | - | RES,22 Ohm,+/-1%,1/16W,G,SMD0402 | KOA SPEER ELECTRONICS, INC. | RK73H1ETTP22R0F | 1 | N | R721 |
|  | N | ND | Y(4) | 79 | 610112J00-017-G | - | RES,200 Ohm,+/-1%,1/16W,G,SMD0402 | KOA SPEER ELECTRONICS, INC. | RK73H1ETTP2000F | 1 | N | R746 |
|  | ND |  | Y(4) | 80 | 61011U901-017-G |  | RES,120Ohm,+/-1%,1/20W,G,SMD0201 | KOA SPEER ELECTRONICS, INC. | RK73H1HTTC1200F | 4 |  | R837,R838,R863,R892 |
|  | N | other | Y(4) | 81 | 610107F00-017-G |  | RES,1KOhm,+/-5%,1/10W,G,SMD0603 | KOA SPEER ELECTRONICS, INC. | RK73B1JTTD102J | 3 | N | R1079,R1081,R1778 |
|  | N | ND | Y(5) | 82 | 611003D00-017-G |  | RES,1KOhm,+/-0.1%,1/16W,G,SMD0402 | KOA SPEER ELECTRONICS, INC. | RN731ETTP1001B25 | 1 | Y | R1112 |
|  | N |  | Y(5) | 83 | 61100QH00-017-G |  | RES,510 Ohm,+/-0.1%,1/16W,G,SMD0402 | KOA SPEER ELECTRONICS, INC. | RN731ETTP5100B25 | 1 | Y | R1113 |
|  | N | ND | Y(4) | 84 | 610103300-017-G | - | RES,100KOhm,+/-5%,1/16W,G,SMD0402 | KOA SPEER ELECTRONICS, INC. | RK73B1ETTP104J | 4 | N | R1251,R1252,R1253,R1254 |
|  | ND | ND | Y(4) | 85 | 61011CY00-017-G |  | RES,5.6KOhm,+/-1%,1/16W,G,SMD0402 | KOA SPEER ELECTRONICS, INC. | RK73H1ETTP5601F | 4 | N | R1266,R1270,R1274,R1278 |
|  | ND | ND | Y(5) | 86 | 61100AH00-017-G |  | RES,10KOhm,+/-0.5%,1/16W,G,SMD0402 | KOA SPEER ELECTRONICS, INC. | RN731ETTP1002D25 | 6 | Y | R1299,R1300,R1301,R1302,R1306,R1309 |
|  | N |  | Y(4) | 87 | 610154700-017-G |  | RES,10KOhm,+/-5%,1/8W,G,SMD0402 | KOA SPEER ELECTRONICS, INC. | SG73P1ETTP103J | 2 |  | R1324,R1326 |
|  | ND | ND | Y(4) | 88 | 61012LR00-017-G |  | RES,1KOhm,+/-0.5%,1/16W,G,SMD0402 | KOA SPEER ELECTRONICS, INC. | RK73H1ETTP1001D | 1 | N | R1481 |
|  | N | ND | Y(4) | 89 | 61011DR00-017-G |  | RES,2.2KOhm,+/-1%,1/16W,G,SMD0402 | KOA SPEER ELECTRONICS, INC. | RK73H1ETTP2201F | 11 | N | R1726,R1727,R1728,R1731,R1732,R1734,R1735,R1736,R1738,R1739,R1740 |
|  | ND | ND | Y(4) | 90 | 610124C00-017-G | - | RES,57.6 Ohm,+/-1%,1/16W,G,SMD0402 | KOA SPEER ELECTRONICS, INC. | RK73H1ETTP57R6F | 4 | N | R1836,R1838,R1839,R1846 |
|  | ND | ND | Y(1) | 91 | 410400T00-214-G |  | EEPROM,M93C46-WMN6TP,2.5~5.5V,1K,3-wire serial,G,SO-8,SMD | ST MICRO ELECTRONICS,INC | M93C46-WMN6TP | 1 | N | U39 |
|  | ND | ND | N | 92 | 34062MW00-309-G |  | CONN,Header,WTB,2X5,V/T,Bla,1.27mm,10u,G,SMD-10 | SAMTEC INC. | FTSH-105-01-L-DV-K-P-TR | 1 |  | J_JTAG_LOM1 |
|  | ND |  | N | 93 | 3406AQH00-317-G |  | CONN,Header,Pin Header,1X6,V/T,Bla,2.54mm,G,SMD-6 | MOLEX INCORPORATED | 87898-0656 | 1 |  | J_UART_LOM1 |
|  | N | ND | N | 94 | 340692800-309-G | - | CONN,Header,Socket,2X30,V/T,Bla,0.5mm,G/F,G,SMD-60 | SAMTEC INC. | QSH-030-01-F-D-A-K-TR | 1 |  | J6 |
|  | ND |  | N | 95 | 340459T00-GRS-G |  | CONN,I/O,HDMI,V/T,Bla,0.5mm,1u,G,SMD-19 | LOTES CO LTD | AHDM0001-P004A | 1 |  | J8 |
|  | ND |  | N | 96 | 3406B5J00-317-G |  | CONN,Header,Socket,V/T,Bla,2mm,15u,G,DIP-18 | MOLEX INCORPORATED | 79107-7008 | 1 |  | J10 |
|  | ND |  | N | 97 | 34064J800-317-G |  | CONN,Header,Socket,2X2,V/T,Bla,2mm,15u,G,DIP-4 | MOLEX INCORPORATED | 79107-7001 | 1 |  | J13 |
|  | ND | ND | N | 98 | 340604M00-600-G | - | CONN,Header,Friction,1X3,V/T,Ivo,2.54mm,G,DIP-3 | FOXCONN TECHNOLOGY CO.,LTD. | HF2803E-P1 | 4 | Y | J19,J20,J21,J22 |
|  | ND |  | N | 99 | 3406A2B00-317-G |  | CONN,Header,WTB,1X4,V/T,Bla,2.54mm,15u,G,DIP-4 | MOLEX INCORPORATED | 171856-1104 | 4 |  | J23,J24,J25,J26 |
|  | ND |  | N | 100 | 3406ARP00-317-G |  | CONN,Header,Power,2X8,V/T,Whi,4.2mm,G,DIP-16 | MOLEX INCORPORATED | 46015-1602 | 1 |  | J100 |
|  | ND |  | N | 101 | 34060VU00-309-G |  | CONN,Pin Header,1X2,V/T,Bla,2.54mm,10u,G,SMD-2 | SAMTEC INC. | TSM-102-01-L-SV-P-TR | 38 |  | J104,J105,J106,J107,J108,J109,J110,J111,J112,J113,J114,J115,J116,J117,J118,J119,J120,J121,J122,J123,J124,J125,J126,J127,J128,J129,J130,J131,J132,J133,J134,J135,J136,J137,J138,J139,J140,J141 |
